# S9S_MB_2U (Grand Teton) — schematic netlist excerpt (pin names and nets, part order shuffled) for the footprints in the layout excerpt that follows; sources: Cadence DE-HDL packaged netlist, KiCad conversion of 03242023_DA0F0TMBIJ0_F0T_Motherboard_J_brd_V01_OCP.brd

C374  Q_CAP  47UF 4V 20% X6S  pkg C0805  page 76 : A = PVCCIN_CPU0 ; B = GND
C1907  Q_CAP  0.1UF 25V 10% X7R  pkg 0402  page 217 : A = VCC_PLD_CORE ; B = GND
PR2521  Q_RES  1 1% EMPTY  pkg 0402LF  page 304 : A = P12V_HSC_SENSE2_P ; B = P12V_HSC_SENSE2_R2_P

(kicad_pcb
	(version 20260206)
	(generator "pcbnew")
	(generator_version "10.0")
	(general
		(thickness 1.6)
		(legacy_teardrops no)
	)
	(paper "A4")
	(title_block
		(title "03242023_DA0F0TMBIJ0_F0T_Motherboard_J_brd_V01_OCP.brd")
		(comment 1 "Grand Teton / footprints 5432-5434 of 6105")
	)
	(layers
		(0 "F.Cu" signal "TOP")
		(4 "In1.Cu" signal "GND")
		(6 "In2.Cu" signal "IN1")
		(8 "In3.Cu" signal "GND1")
		(10 "In4.Cu" signal "IN2")
		(12 "In5.Cu" signal "GND2")
		(14 "In6.Cu" signal "IN3")
		(16 "In7.Cu" signal "GND3")
		(18 "In8.Cu" signal "VCC")
		(20 "In9.Cu" signal "VCC1")
		(22 "In10.Cu" signal "GND4")
		(24 "In11.Cu" signal "IN4")
		(26 "In12.Cu" signal "GND5")
		(28 "In13.Cu" signal "IN5")
		(30 "In14.Cu" signal "GND6")
		(32 "In15.Cu" signal "IN6")
		(34 "In16.Cu" signal "GND7")
		(2 "B.Cu" signal "BOTTOM")
		(9 "F.Adhes" user "F.Adhesive")
		(11 "B.Adhes" user "B.Adhesive")
		(13 "F.Paste" user "Package Geometry/Pastemask Top")
		(15 "B.Paste" user "Package Geometry/Pastemask Bottom")
		(5 "F.SilkS" user "Ref Des/Silkscreen Top")
		(7 "B.SilkS" user "Ref Des/Silkscreen Bottom")
		(1 "F.Mask" user "Board Geometry/Soldermask Top")
		(3 "B.Mask" user "Board Geometry/Soldermask Bottom")
		(17 "Dwgs.User" user "User.Drawings")
		(19 "Cmts.User" user "User.Comments")
		(21 "Eco1.User" user "User.Eco1")
		(23 "Eco2.User" user "User.Eco2")
		(25 "Edge.Cuts" user "Board Geometry/Outline")
		(27 "Margin" user)
		(31 "F.CrtYd" user "Package Geometry/Place Bound Top")
		(29 "B.CrtYd" user "Package Geometry/Place Bound Bottom")
		(35 "F.Fab" user "Ref Des/Assembly Top")
		(33 "B.Fab" user "Ref Des/Assembly Bottom")
	)
	(footprint ""
		(layer "B.Cu")
		(at 291.004498 -400.999452 -90)
		(property "Reference" "PR2521"
			(at 0 0 90)
			(layer "B.SilkS")
			(hide yes)
			(effects
				(font
					(size 1.27 1.27)
				)
				(justify mirror)
			)
		)
		(property "Value" ""
			(at 0 0 90)
			(layer "B.Fab")
			(effects
				(font
					(size 1.27 1.27)
				)
				(justify mirror)
			)
		)
		(duplicate_pad_numbers_are_jumpers no)
		(fp_line
			(start -0.7874 0.4064)
			(end 0.7874 0.4064)
			(stroke
				(width 0.1524)
				(type default)
			)
			(layer "B.SilkS")
		)
		(fp_line
			(start 0.7874 0.4064)
			(end 0.7874 -0.4064)
			(stroke
				(width 0.1524)
				(type default)
			)
			(layer "B.SilkS")
		)
		(fp_line
			(start -0.7874 -0.4064)
			(end -0.7874 0.4064)
			(stroke
				(width 0.1524)
				(type default)
			)
			(layer "B.SilkS")
		)
		(fp_line
			(start 0.7874 -0.4064)
			(end -0.7874 -0.4064)
			(stroke
				(width 0.1524)
				(type default)
			)
			(layer "B.SilkS")
		)
		(fp_line
			(start -0.67945 0.3048)
			(end -0.120396 0.3048)
			(stroke
				(width 0.1)
				(type default)
			)
			(layer "B.Fab")
		)
		(fp_line
			(start -0.120396 0.3048)
			(end -0.120396 0.2794)
			(stroke
				(width 0.1)
				(type default)
			)
			(layer "B.Fab")
		)
		(fp_line
			(start 0.12065 0.3048)
			(end 0.67945 0.3048)
			(stroke
				(width 0.1)
				(type default)
			)
			(layer "B.Fab")
		)
		(fp_line
			(start 0.67945 0.3048)
			(end 0.67945 -0.305054)
			(stroke
				(width 0.1)
				(type default)
			)
			(layer "B.Fab")
		)
		(fp_line
			(start -0.120396 0.2794)
			(end 0.12065 0.2794)
			(stroke
				(width 0.1)
				(type default)
			)
			(layer "B.Fab")
		)
		(fp_line
			(start 0.12065 0.2794)
			(end 0.12065 0.3048)
			(stroke
				(width 0.1)
				(type default)
			)
			(layer "B.Fab")
		)
		(fp_line
			(start -0.12065 -0.2794)
			(end -0.12065 -0.3048)
			(stroke
				(width 0.1)
				(type default)
			)
			(layer "B.Fab")
		)
		(fp_line
			(start 0.12065 -0.2794)
			(end -0.12065 -0.2794)
			(stroke
				(width 0.1)
				(type default)
			)
			(layer "B.Fab")
		)
		(fp_line
			(start -0.67945 -0.3048)
			(end -0.67945 0.3048)
			(stroke
				(width 0.1)
				(type default)
			)
			(layer "B.Fab")
		)
		(fp_line
			(start -0.12065 -0.3048)
			(end -0.67945 -0.3048)
			(stroke
				(width 0.1)
				(type default)
			)
			(layer "B.Fab")
		)
		(fp_line
			(start 0.12065 -0.305054)
			(end 0.12065 -0.2794)
			(stroke
				(width 0.1)
				(type default)
			)
			(layer "B.Fab")
		)
		(fp_line
			(start 0.67945 -0.305054)
			(end 0.12065 -0.305054)
			(stroke
				(width 0.1)
				(type default)
			)
			(layer "B.Fab")
		)
		(pad "1" smd circle
			(at 0.40005 0 90)
			(size 0 0)
			(layers "B.Cu" "B.Mask" "B.Paste")
			(net "P12V_HSC_SENSE2_P")
		)
		(pad "2" smd circle
			(at -0.40005 0 90)
			(size 0 0)
			(layers "B.Cu" "B.Mask" "B.Paste")
			(net "P12V_HSC_SENSE2_R2_P")
		)
	)
	(footprint ""
		(layer "B.Cu")
		(at 176.955704 -114.575336)
		(property "Reference" "C1907"
			(at 0 0 0)
			(layer "B.SilkS")
			(hide yes)
			(effects
				(font
					(size 1.27 1.27)
				)
				(justify mirror)
			)
		)
		(property "Value" ""
			(at 0 0 0)
			(layer "B.Fab")
			(effects
				(font
					(size 1.27 1.27)
				)
				(justify mirror)
			)
		)
		(duplicate_pad_numbers_are_jumpers no)
		(fp_line
			(start -0.69215 -0.2921)
			(end -0.69215 0.2921)
			(stroke
				(width 0.1524)
				(type default)
			)
			(layer "B.SilkS")
		)
		(fp_line
			(start -0.69215 0.2921)
			(end 0.69215 0.2921)
			(stroke
				(width 0.1524)
				(type default)
			)
			(layer "B.SilkS")
		)
		(fp_line
			(start 0.69215 -0.2921)
			(end -0.69215 -0.2921)
			(stroke
				(width 0.1524)
				(type default)
			)
			(layer "B.SilkS")
		)
		(fp_line
			(start 0.69215 0.2921)
			(end 0.69215 -0.2921)
			(stroke
				(width 0.1524)
				(type default)
			)
			(layer "B.SilkS")
		)
		(fp_line
			(start -0.51435 -0.2794)
			(end -0.51435 0.2794)
			(stroke
				(width 0.1)
				(type default)
			)
			(layer "B.Fab")
		)
		(fp_line
			(start -0.51435 0.2794)
			(end 0.51435 0.2794)
			(stroke
				(width 0.1)
				(type default)
			)
			(layer "B.Fab")
		)
		(fp_line
			(start 0.51435 -0.2794)
			(end -0.51435 -0.2794)
			(stroke
				(width 0.1)
				(type default)
			)
			(layer "B.Fab")
		)
		(fp_line
			(start 0.51435 0.2794)
			(end 0.51435 -0.2794)
			(stroke
				(width 0.1)
				(type default)
			)
			(layer "B.Fab")
		)
		(pad "1" smd circle
			(at 0.40005 0 180)
			(size 0 0)
			(layers "B.Cu" "B.Mask" "B.Paste")
			(net "VCC_PLD_CORE")
		)
		(pad "2" smd circle
			(at -0.40005 0 180)
			(size 0 0)
			(layers "B.Cu" "B.Mask" "B.Paste")
			(net "GND")
		)
		(zone
			(layer "B.Cu")
			(hatch none 0.5)
			(connect_pads
				(clearance 0)
			)
			(min_thickness 0.25)
			(keepout
				(tracks not_allowed)
				(vias allowed)
				(pads allowed)
				(copperpour not_allowed)
				(footprints allowed)
			)
			(placement
				(enabled no)
				(sheetname "")
			)
			(fill
				(thermal_gap 0.5)
				(thermal_bridge_width 0.5)
				(island_removal_mode 0)
			)
			(polygon
				(pts
					(xy 177.146204 -114.487706) (xy 177.054764 -114.42954) (xy 176.855374 -114.42954) (xy 176.765204 -114.487706)
					(xy 176.765204 -114.662966) (xy 176.855374 -114.721386) (xy 177.054764 -114.721386) (xy 177.146204 -114.66322)
				)
			)
		)
	)
	(footprint ""
		(layer "B.Cu")
		(at 359.960418 -294.009826)
		(property "Reference" "C374"
			(at 0 0 0)
			(layer "B.SilkS")
			(hide yes)
			(effects
				(font
					(size 1.27 1.27)
				)
				(justify mirror)
			)
		)
		(property "Value" ""
			(at 0 0 0)
			(layer "B.Fab")
			(effects
				(font
					(size 1.27 1.27)
				)
				(justify mirror)
			)
		)
		(duplicate_pad_numbers_are_jumpers no)
		(fp_line
			(start -1.524 -0.762)
			(end -1.524 0.762)
			(stroke
				(width 0.1524)
				(type default)
			)
			(layer "B.SilkS")
		)
		(fp_line
			(start -1.524 0.762)
			(end 1.524 0.762)
			(stroke
				(width 0.1524)
				(type default)
			)
			(layer "B.SilkS")
		)
		(fp_line
			(start 1.524 -0.762)
			(end -1.524 -0.762)
			(stroke
				(width 0.1524)
				(type default)
			)
			(layer "B.SilkS")
		)
		(fp_line
			(start 1.524 0.762)
			(end 1.524 -0.762)
			(stroke
				(width 0.1524)
				(type default)
			)
			(layer "B.SilkS")
		)
		(fp_line
			(start -1.1049 -0.724916)
			(end 1.1049 -0.724916)
			(stroke
				(width 0.1)
				(type default)
			)
			(layer "B.Fab")
		)
		(fp_line
			(start -1.1049 0.724916)
			(end -1.1049 -0.724916)
			(stroke
				(width 0.1)
				(type default)
			)
			(layer "B.Fab")
		)
		(fp_line
			(start 1.1049 -0.724916)
			(end 1.1049 0.724916)
			(stroke
				(width 0.1)
				(type default)
			)
			(layer "B.Fab")
		)
		(fp_line
			(start 1.1049 0.724916)
			(end -1.1049 0.724916)
			(stroke
				(width 0.1)
				(type default)
			)
			(layer "B.Fab")
		)
		(pad "1" smd rect
			(at 0.889 0)
			(size 1.016 1.27)
			(layers "B.Cu" "B.Mask" "B.Paste")
			(net "PVCCIN_CPU0")
		)
		(pad "2" smd rect
			(at -0.889 0)
			(size 1.016 1.27)
			(layers "B.Cu" "B.Mask" "B.Paste")
			(net "GND")
		)
	)
)
